# TIMECARD (Time Appliance Project (Time Card)) — schematic netlist excerpt (pin names and nets, part order shuffled) for the footprints in the layout excerpt that follows; sources: Cadence DE-HDL packaged netlist, KiCad conversion of R4006-B0001-02_R01.brd

C51  CAPACITOR  12PF 50V 5%  pkg SMC_0201R  page 20 : \1\ = UNNAMED_9_CAPACITOR_I17_1 ; \2\ = SG
R477  RESISTOR  100KOHM 1%  pkg SMC_0402R_H016  page 24 : \1\ = XP3R3V_FPGA ; \2\ = FPGA_EEPROM_I2C_SCL

(kicad_pcb
	(version 20260206)
	(generator "pcbnew")
	(generator_version "10.0")
	(general
		(thickness 1.6)
		(legacy_teardrops no)
	)
	(paper "A4")
	(title_block
		(title "timecard-production-celestica-r4006 — R4006-B0001-02_R01.brd")
		(comment 1 "Time Appliance Project (Time Card) / footprints 480-481 of 1113")
	)
	(layers
		(0 "F.Cu" signal "TOP")
		(4 "In1.Cu" signal "L02_GND1")
		(6 "In2.Cu" signal "L03_SIG1")
		(8 "In3.Cu" signal "L04_GND2")
		(10 "In4.Cu" signal "L05_VCC1")
		(12 "In5.Cu" signal "L06_VCC2")
		(14 "In6.Cu" signal "L07_GND3")
		(16 "In7.Cu" signal "L08_SIG2")
		(18 "In8.Cu" signal "L09_GND4")
		(2 "B.Cu" signal "BOTTOM")
		(9 "F.Adhes" user "F.Adhesive")
		(11 "B.Adhes" user "B.Adhesive")
		(13 "F.Paste" user "Package Geometry/Pastemask Top")
		(15 "B.Paste" user "Package Geometry/Pastemask Bottom")
		(5 "F.SilkS" user "Ref Des/Silkscreen Top")
		(7 "B.SilkS" user "Ref Des/Silkscreen Bottom")
		(1 "F.Mask" user "Board Geometry/Soldermask Top")
		(3 "B.Mask" user "Board Geometry/Soldermask Bottom")
		(17 "Dwgs.User" user "User.Drawings")
		(19 "Cmts.User" user "User.Comments")
		(21 "Eco1.User" user "User.Eco1")
		(23 "Eco2.User" user "User.Eco2")
		(25 "Edge.Cuts" user "Board Geometry/Outline")
		(27 "Margin" user)
		(31 "F.CrtYd" user "Package Geometry/Place Bound Top")
		(29 "B.CrtYd" user "Package Geometry/Place Bound Bottom")
		(35 "F.Fab" user "Ref Des/Assembly Top")
		(33 "B.Fab" user "Ref Des/Assembly Bottom")
	)
	(footprint ""
		(layer "F.Cu")
		(at 133.858 -20.828 180)
		(property "Reference" "R477"
			(at 0.127 5.29463 0)
			(unlocked yes)
			(layer "F.SilkS")
			(effects
				(font
					(size 0.7874 0.5842)
					(thickness 0.1524)
				)
			)
		)
		(property "Value" "VAL*"
			(at 0.02032 2.13233 180)
			(unlocked yes)
			(layer "F.Fab")
			(hide yes)
			(effects
				(font
					(size 0.7874 0.5842)
					(thickness 0.1524)
				)
			)
		)
		(property "Tolerance" "TOL*"
			(at 0.044704 3.05435 180)
			(unlocked yes)
			(layer "Cmts.User")
			(hide yes)
			(effects
				(font
					(size 0.7874 0.5842)
					(thickness 0.1524)
				)
			)
		)
		(property "User Part Number" "PARTNUM*"
			(at 0.02032 4.024884 180)
			(unlocked yes)
			(layer "Cmts.User")
			(hide yes)
			(effects
				(font
					(size 0.7874 0.5842)
					(thickness 0.1524)
				)
			)
		)
		(property "Device Type" "RESISTOR-G155-11003-01,100KOHMA"
			(at 0.008382 1.210564 180)
			(unlocked yes)
			(layer "F.Fab")
			(hide yes)
			(effects
				(font
					(size 0.7874 0.5842)
					(thickness 0.1524)
				)
			)
		)
		(duplicate_pad_numbers_are_jumpers no)
		(fp_line
			(start 1.143 0.5588)
			(end 1.143 -0.5588)
			(stroke
				(width 0.1)
				(type default)
			)
			(layer "F.SilkS")
		)
		(fp_line
			(start 1.143 -0.5588)
			(end -1.143 -0.5588)
			(stroke
				(width 0.1)
				(type default)
			)
			(layer "F.SilkS")
		)
		(fp_line
			(start -1.143 0.5588)
			(end 1.143 0.5588)
			(stroke
				(width 0.1)
				(type default)
			)
			(layer "F.SilkS")
		)
		(fp_line
			(start -1.143 -0.5588)
			(end -1.143 0.5588)
			(stroke
				(width 0.1)
				(type default)
			)
			(layer "F.SilkS")
		)
		(fp_poly
			(pts
				(xy -1.143 0.5588) (xy 1.143 0.5588) (xy 1.143 -0.5588) (xy -1.143 -0.5588)
			)
			(stroke
				(width 0)
				(type default)
			)
			(fill no)
			(layer "F.CrtYd")
		)
		(fp_line
			(start 0.508 0.3048)
			(end 0.508 -0.3048)
			(stroke
				(width 0.1)
				(type default)
			)
			(layer "F.Fab")
		)
		(fp_line
			(start 0.508 -0.3048)
			(end -0.508 -0.3048)
			(stroke
				(width 0.1)
				(type default)
			)
			(layer "F.Fab")
		)
		(fp_line
			(start -0.508 0.3048)
			(end 0.508 0.3048)
			(stroke
				(width 0.1)
				(type default)
			)
			(layer "F.Fab")
		)
		(fp_line
			(start -0.508 -0.3048)
			(end -0.508 0.3048)
			(stroke
				(width 0.1)
				(type default)
			)
			(layer "F.Fab")
		)
		(pad "1" smd rect
			(at -0.5334 0 180)
			(size 0.7112 0.6096)
			(layers "F.Cu" "F.Mask" "F.Paste")
			(net "XP3R3V_FPGA")
		)
		(pad "2" smd rect
			(at 0.5334 0 180)
			(size 0.7112 0.6096)
			(layers "F.Cu" "F.Mask" "F.Paste")
			(net "FPGA_EEPROM_I2C_SCL")
		)
		(zone
			(layer "F.Cu")
			(hatch none 0.5)
			(connect_pads
				(clearance 0)
			)
			(min_thickness 0.25)
			(keepout
				(tracks allowed)
				(vias not_allowed)
				(pads allowed)
				(copperpour not_allowed)
				(footprints allowed)
			)
			(placement
				(enabled no)
				(sheetname "")
			)
			(fill
				(thermal_gap 0.5)
				(thermal_bridge_width 0.5)
				(island_removal_mode 0)
			)
			(polygon
				(pts
					(xy 133.9342 -21.1328) (xy 133.7818 -21.1328) (xy 133.7818 -20.5232) (xy 133.9342 -20.5232)
				)
			)
		)
		(zone
			(layer "F.Cu")
			(hatch none 0.5)
			(connect_pads
				(clearance 0)
			)
			(min_thickness 0.25)
			(keepout
				(tracks not_allowed)
				(vias allowed)
				(pads allowed)
				(copperpour not_allowed)
				(footprints allowed)
			)
			(placement
				(enabled no)
				(sheetname "")
			)
			(fill
				(thermal_gap 0.5)
				(thermal_bridge_width 0.5)
				(island_removal_mode 0)
			)
			(polygon
				(pts
					(xy 133.9342 -21.1328) (xy 133.7818 -21.1328) (xy 133.7818 -20.5232) (xy 133.9342 -20.5232)
				)
			)
		)
	)
	(footprint ""
		(layer "F.Cu")
		(at 92.372942 -61.0108 90)
		(property "Reference" "C51"
			(at -2.95275 0.337058 0)
			(unlocked yes)
			(layer "F.SilkS")
			(effects
				(font
					(size 0.635 0.4064)
					(thickness 0.1524)
				)
			)
		)
		(property "Value" "VAL*"
			(at 0.193548 2.13614 90)
			(unlocked yes)
			(layer "F.Fab")
			(hide yes)
			(effects
				(font
					(size 0.7874 0.5842)
					(thickness 0.1524)
				)
			)
		)
		(property "Tolerance" "TOL*"
			(at 0.216154 3.1496 90)
			(unlocked yes)
			(layer "Cmts.User")
			(hide yes)
			(effects
				(font
					(size 0.7874 0.5842)
					(thickness 0.1524)
				)
			)
		)
		(property "Device Type" "CAPACITOR-G104-0A120-FJ,12PF,5%"
			(at 0.184404 1.180592 90)
			(unlocked yes)
			(layer "F.Fab")
			(hide yes)
			(effects
				(font
					(size 0.7874 0.5842)
					(thickness 0.1524)
				)
			)
		)
		(property "User Part Number" "PARTNUM*"
			(at 0.216154 4.185666 90)
			(unlocked yes)
			(layer "Cmts.User")
			(hide yes)
			(effects
				(font
					(size 0.7874 0.5842)
					(thickness 0.1524)
				)
			)
		)
		(duplicate_pad_numbers_are_jumpers no)
		(fp_line
			(start 0.671322 -0.4445)
			(end 0.671322 0.4445)
			(stroke
				(width 0.1)
				(type default)
			)
			(layer "F.SilkS")
		)
		(fp_line
			(start -0.671322 -0.4445)
			(end 0.671322 -0.4445)
			(stroke
				(width 0.1)
				(type default)
			)
			(layer "F.SilkS")
		)
		(fp_line
			(start 0.671322 0.4445)
			(end -0.671322 0.4445)
			(stroke
				(width 0.1)
				(type default)
			)
			(layer "F.SilkS")
		)
		(fp_line
			(start -0.671322 0.4445)
			(end -0.671322 -0.4445)
			(stroke
				(width 0.1)
				(type default)
			)
			(layer "F.SilkS")
		)
		(fp_rect
			(start -0.671322 -0.4445)
			(end 0.671322 0.4445)
			(stroke
				(width 0)
				(type default)
			)
			(fill no)
			(layer "F.CrtYd")
		)
		(fp_line
			(start 0.31496 -0.1651)
			(end -0.31496 -0.1651)
			(stroke
				(width 0.1)
				(type default)
			)
			(layer "F.Fab")
		)
		(fp_line
			(start -0.31496 -0.1651)
			(end -0.31496 0.1651)
			(stroke
				(width 0.1)
				(type default)
			)
			(layer "F.Fab")
		)
		(fp_line
			(start 0.31496 0.1651)
			(end 0.31496 -0.1651)
			(stroke
				(width 0.1)
				(type default)
			)
			(layer "F.Fab")
		)
		(fp_line
			(start -0.31496 0.1651)
			(end 0.31496 0.1651)
			(stroke
				(width 0.1)
				(type default)
			)
			(layer "F.Fab")
		)
		(pad "1" smd rect
			(at -0.264922 0 90)
			(size 0.3048 0.381)
			(layers "F.Cu" "F.Mask" "F.Paste")
			(net "UNNAMED_9_CAPACITOR_I17_1")
		)
		(pad "2" smd rect
			(at 0.264922 0 90)
			(size 0.3048 0.381)
			(layers "F.Cu" "F.Mask" "F.Paste")
			(net "SG")
		)
		(zone
			(layer "F.Cu")
			(hatch none 0.5)
			(connect_pads
				(clearance 0)
			)
			(min_thickness 0.25)
			(keepout
				(tracks allowed)
				(vias not_allowed)
				(pads allowed)
				(copperpour not_allowed)
				(footprints allowed)
			)
			(placement
				(enabled no)
				(sheetname "")
			)
			(fill
				(thermal_gap 0.5)
				(thermal_bridge_width 0.5)
				(island_removal_mode 0)
			)
			(polygon
				(pts
					(xy 92.182442 -60.898278) (xy 92.563442 -60.898278) (xy 92.563442 -61.123322) (xy 92.182442 -61.123322)
				)
			)
		)
	)
)
